(kicad_pcb
	(version 20260206)
	(generator "pcbnew")
	(generator_version "10.0")
	(general
		(thickness 1.6)
		(legacy_teardrops no)
	)
	(paper "A4")
	(title_block
		(title "pdpb — Lightning_PDPB_BRD.brd")
		(comment 1 "Lightning (Wiwynn / Facebook NVMe JBOF) / footprints 317-323 of 1140")
	)
	(layers
		(0 "F.Cu" signal "TOP")
		(4 "In1.Cu" signal "L2GND")
		(6 "In2.Cu" signal "L3")
		(8 "In3.Cu" signal "L4VCC")
		(10 "In4.Cu" signal "L5VCC")
		(12 "In5.Cu" signal "L6")
		(14 "In6.Cu" signal "L7GND")
		(2 "B.Cu" signal "BOTTOM")
		(9 "F.Adhes" user "F.Adhesive")
		(11 "B.Adhes" user "B.Adhesive")
		(13 "F.Paste" user "Package Geometry/Pastemask Top")
		(15 "B.Paste" user "Package Geometry/Pastemask Bottom")
		(5 "F.SilkS" user "Ref Des/Silkscreen Top")
		(7 "B.SilkS" user "Ref Des/Silkscreen Bottom")
		(1 "F.Mask" user "Board Geometry/Soldermask Top")
		(3 "B.Mask" user "Board Geometry/Soldermask Bottom")
		(17 "Dwgs.User" user "User.Drawings")
		(19 "Cmts.User" user "User.Comments")
		(21 "Eco1.User" user "User.Eco1")
		(23 "Eco2.User" user "User.Eco2")
		(25 "Edge.Cuts" user "Board Geometry/Outline")
		(27 "Margin" user)
		(31 "F.CrtYd" user "Package Geometry/Place Bound Top")
		(29 "B.CrtYd" user "Package Geometry/Place Bound Bottom")
		(35 "F.Fab" user "Ref Des/Assembly Top")
		(33 "B.Fab" user "Ref Des/Assembly Bottom")
	)
	(footprint ""
		(layer "F.Cu")
		(at 219.71 -194.5386 180)
		(property "Reference" "PC1227"
			(at 0 0 180)
			(layer "F.SilkS")
			(hide yes)
			(effects
				(font
					(size 1.27 1.27)
				)
			)
		)
		(property "Value" "SCD1U50V3KX-GP"
			(at 0 -2.8194 180)
			(unlocked yes)
			(layer "F.Fab")
			(hide yes)
			(effects
				(font
					(size 1.016 1.016)
					(thickness 0.1524)
				)
			)
		)
		(property "Device Type" "C603H36"
			(at 0 -4.3434 180)
			(unlocked yes)
			(layer "F.Fab")
			(hide yes)
			(effects
				(font
					(size 1.016 1.016)
					(thickness 0.1524)
				)
			)
		)
		(duplicate_pad_numbers_are_jumpers no)
		(fp_line
			(start 0.508 0)
			(end -0.508 0)
			(stroke
				(width 0.2032)
				(type default)
			)
			(layer "F.SilkS")
		)
		(fp_rect
			(start -0.5842 1.3335)
			(end 0.5842 -1.3335)
			(stroke
				(width 0)
				(type default)
			)
			(fill no)
			(layer "F.CrtYd")
		)
		(fp_rect
			(start -0.5842 1.3335)
			(end 0.5842 -1.3335)
			(stroke
				(width 0)
				(type default)
			)
			(fill no)
			(layer "F.Fab")
		)
		(pad "1" smd custom
			(at 0 -0.762 180)
			(size 0.2159 0.2159)
			(layers "F.Cu" "F.Mask" "F.Paste")
			(net "P12V_SSD3")
			(options
				(clearance outline)
				(anchor circle)
			)
			(primitives
				(gr_poly
					(pts
						(arc
							(start -0.3302 -0.4318)
							(mid -0.402042 -0.402042)
							(end -0.4318 -0.3302)
						)
						(arc
							(start -0.4318 0.3302)
							(mid -0.402042 0.402042)
							(end -0.3302 0.4318)
						)
						(arc
							(start 0.3302 0.4318)
							(mid 0.402042 0.402042)
							(end 0.4318 0.3302)
						)
						(arc
							(start 0.4318 -0.3302)
							(mid 0.402042 -0.402042)
							(end 0.3302 -0.4318)
						)
					)
					(width 0)
					(fill yes)
				)
			)
		)
		(pad "2" smd custom
			(at 0 0.762 180)
			(size 0.2159 0.2159)
			(layers "F.Cu" "F.Mask" "F.Paste")
			(net "GND")
			(options
				(clearance outline)
				(anchor circle)
			)
			(primitives
				(gr_poly
					(pts
						(arc
							(start -0.3302 -0.4318)
							(mid -0.402042 -0.402042)
							(end -0.4318 -0.3302)
						)
						(arc
							(start -0.4318 0.3302)
							(mid -0.402042 0.402042)
							(end -0.3302 0.4318)
						)
						(arc
							(start 0.3302 0.4318)
							(mid 0.402042 0.402042)
							(end 0.4318 0.3302)
						)
						(arc
							(start 0.4318 -0.3302)
							(mid 0.402042 -0.402042)
							(end 0.3302 -0.4318)
						)
					)
					(width 0)
					(fill yes)
				)
			)
		)
	)
	(footprint ""
		(layer "F.Cu")
		(at 28.8671 -94.5261 180)
		(property "Reference" "R9840"
			(at 0 0 180)
			(layer "F.SilkS")
			(hide yes)
			(effects
				(font
					(size 1.27 1.27)
				)
			)
		)
		(property "Value" "47KR2J-2-GP"
			(at 0.064008 -3.993896 180)
			(unlocked yes)
			(layer "F.Fab")
			(hide yes)
			(effects
				(font
					(size 1.016 1.016)
					(thickness 0.1524)
				)
			)
		)
		(property "Device Type" "R402H16"
			(at 0.064008 -5.517896 180)
			(unlocked yes)
			(layer "F.Fab")
			(hide yes)
			(effects
				(font
					(size 1.016 1.016)
					(thickness 0.1524)
				)
			)
		)
		(duplicate_pad_numbers_are_jumpers no)
		(fp_line
			(start 0.508 -0.9398)
			(end -0.508 -0.9398)
			(stroke
				(width 0.1524)
				(type default)
			)
			(layer "F.SilkS")
		)
		(fp_line
			(start -0.508 -0.9398)
			(end -0.508 0.9398)
			(stroke
				(width 0.1524)
				(type default)
			)
			(layer "F.SilkS")
		)
		(fp_rect
			(start -0.508 0.9398)
			(end 0.508 -0.9398)
			(stroke
				(width 0)
				(type default)
			)
			(fill no)
			(layer "F.CrtYd")
		)
		(fp_rect
			(start -0.508 0.9398)
			(end 0.508 -0.9398)
			(stroke
				(width 0)
				(type default)
			)
			(fill no)
			(layer "F.Fab")
		)
		(pad "1" smd custom
			(at 0 -0.4445 180)
			(size 0.1397 0.1397)
			(layers "F.Cu" "F.Mask" "F.Paste")
			(net "P12V")
			(options
				(clearance outline)
				(anchor circle)
			)
			(primitives
				(gr_poly
					(pts
						(arc
							(start -0.1778 -0.2794)
							(mid -0.249642 -0.249642)
							(end -0.2794 -0.1778)
						)
						(arc
							(start -0.2794 0.1778)
							(mid -0.249642 0.249642)
							(end -0.1778 0.2794)
						)
						(arc
							(start 0.1778 0.2794)
							(mid 0.249642 0.249642)
							(end 0.2794 0.1778)
						)
						(arc
							(start 0.2794 -0.1778)
							(mid 0.249642 -0.249642)
							(end 0.1778 -0.2794)
						)
					)
					(width 0)
					(fill yes)
				)
			)
		)
		(pad "2" smd custom
			(at 0 0.4445 180)
			(size 0.1397 0.1397)
			(layers "F.Cu" "F.Mask" "F.Paste")
			(net "P12V_MOST9_GATE")
			(options
				(clearance outline)
				(anchor circle)
			)
			(primitives
				(gr_poly
					(pts
						(arc
							(start -0.1778 -0.2794)
							(mid -0.249642 -0.249642)
							(end -0.2794 -0.1778)
						)
						(arc
							(start -0.2794 0.1778)
							(mid -0.249642 0.249642)
							(end -0.1778 0.2794)
						)
						(arc
							(start 0.1778 0.2794)
							(mid 0.249642 0.249642)
							(end 0.2794 0.1778)
						)
						(arc
							(start 0.2794 -0.1778)
							(mid 0.249642 -0.249642)
							(end 0.1778 -0.2794)
						)
					)
					(width 0)
					(fill yes)
				)
			)
		)
	)
	(footprint ""
		(layer "F.Cu")
		(at 87.63 -418.338 180)
		(property "Reference" "R9608"
			(at 0 0 180)
			(layer "F.SilkS")
			(hide yes)
			(effects
				(font
					(size 1.27 1.27)
				)
			)
		)
		(property "Value" "10R2F-L-GP"
			(at 0.064008 -3.993896 180)
			(unlocked yes)
			(layer "F.Fab")
			(hide yes)
			(effects
				(font
					(size 1.016 1.016)
					(thickness 0.1524)
				)
			)
		)
		(property "Device Type" "R402H14"
			(at 0.064008 -5.517896 180)
			(unlocked yes)
			(layer "F.Fab")
			(hide yes)
			(effects
				(font
					(size 1.016 1.016)
					(thickness 0.1524)
				)
			)
		)
		(duplicate_pad_numbers_are_jumpers no)
		(fp_line
			(start 0.508 -0.9398)
			(end -0.508 -0.9398)
			(stroke
				(width 0.1524)
				(type default)
			)
			(layer "F.SilkS")
		)
		(fp_line
			(start -0.508 -0.9398)
			(end -0.508 0.9398)
			(stroke
				(width 0.1524)
				(type default)
			)
			(layer "F.SilkS")
		)
		(fp_rect
			(start -0.508 0.9398)
			(end 0.508 -0.9398)
			(stroke
				(width 0)
				(type default)
			)
			(fill no)
			(layer "F.CrtYd")
		)
		(fp_rect
			(start -0.508 0.9398)
			(end 0.508 -0.9398)
			(stroke
				(width 0)
				(type default)
			)
			(fill no)
			(layer "F.Fab")
		)
		(pad "1" smd custom
			(at 0 -0.4445 180)
			(size 0.1397 0.1397)
			(layers "F.Cu" "F.Mask" "F.Paste")
			(net "SSD_PRSNT_NET10")
			(options
				(clearance outline)
				(anchor circle)
			)
			(primitives
				(gr_poly
					(pts
						(arc
							(start -0.1778 -0.2794)
							(mid -0.249642 -0.249642)
							(end -0.2794 -0.1778)
						)
						(arc
							(start -0.2794 0.1778)
							(mid -0.249642 0.249642)
							(end -0.1778 0.2794)
						)
						(arc
							(start 0.1778 0.2794)
							(mid 0.249642 0.249642)
							(end 0.2794 0.1778)
						)
						(arc
							(start 0.2794 -0.1778)
							(mid 0.249642 -0.249642)
							(end 0.1778 -0.2794)
						)
					)
					(width 0)
					(fill yes)
				)
			)
		)
		(pad "2" smd custom
			(at 0 0.4445 180)
			(size 0.1397 0.1397)
			(layers "F.Cu" "F.Mask" "F.Paste")
			(net "SSD_PRSNT10")
			(options
				(clearance outline)
				(anchor circle)
			)
			(primitives
				(gr_poly
					(pts
						(arc
							(start -0.1778 -0.2794)
							(mid -0.249642 -0.249642)
							(end -0.2794 -0.1778)
						)
						(arc
							(start -0.2794 0.1778)
							(mid -0.249642 0.249642)
							(end -0.1778 0.2794)
						)
						(arc
							(start 0.1778 0.2794)
							(mid 0.249642 0.249642)
							(end 0.2794 0.1778)
						)
						(arc
							(start 0.2794 -0.1778)
							(mid 0.249642 -0.249642)
							(end 0.1778 -0.2794)
						)
					)
					(width 0)
					(fill yes)
				)
			)
		)
	)
	(footprint ""
		(layer "F.Cu")
		(at 208.534 -300.228)
		(property "Reference" "R9762"
			(at 0 0 0)
			(layer "F.SilkS")
			(hide yes)
			(effects
				(font
					(size 1.27 1.27)
				)
			)
		)
		(property "Value" "4K7R2J-2-GP"
			(at 0.064008 -3.993896 0)
			(unlocked yes)
			(layer "F.Fab")
			(hide yes)
			(effects
				(font
					(size 1.016 1.016)
					(thickness 0.1524)
				)
			)
		)
		(property "Device Type" "R402H16"
			(at 0.064008 -5.517896 0)
			(unlocked yes)
			(layer "F.Fab")
			(hide yes)
			(effects
				(font
					(size 1.016 1.016)
					(thickness 0.1524)
				)
			)
		)
		(duplicate_pad_numbers_are_jumpers no)
		(fp_line
			(start -0.508 -0.9398)
			(end -0.508 0.9398)
			(stroke
				(width 0.1524)
				(type default)
			)
			(layer "F.SilkS")
		)
		(fp_line
			(start 0.508 -0.9398)
			(end -0.508 -0.9398)
			(stroke
				(width 0.1524)
				(type default)
			)
			(layer "F.SilkS")
		)
		(fp_rect
			(start -0.508 0.9398)
			(end 0.508 -0.9398)
			(stroke
				(width 0)
				(type default)
			)
			(fill no)
			(layer "F.CrtYd")
		)
		(fp_rect
			(start -0.508 0.9398)
			(end 0.508 -0.9398)
			(stroke
				(width 0)
				(type default)
			)
			(fill no)
			(layer "F.Fab")
		)
		(pad "1" smd custom
			(at 0 -0.4445)
			(size 0.1397 0.1397)
			(layers "F.Cu" "F.Mask" "F.Paste")
			(net "SSD2_PWREN")
			(options
				(clearance outline)
				(anchor circle)
			)
			(primitives
				(gr_poly
					(pts
						(arc
							(start -0.1778 -0.2794)
							(mid -0.249642 -0.249642)
							(end -0.2794 -0.1778)
						)
						(arc
							(start -0.2794 0.1778)
							(mid -0.249642 0.249642)
							(end -0.1778 0.2794)
						)
						(arc
							(start 0.1778 0.2794)
							(mid 0.249642 0.249642)
							(end 0.2794 0.1778)
						)
						(arc
							(start 0.2794 -0.1778)
							(mid 0.249642 -0.249642)
							(end 0.1778 -0.2794)
						)
					)
					(width 0)
					(fill yes)
				)
			)
		)
		(pad "2" smd custom
			(at 0 0.4445)
			(size 0.1397 0.1397)
			(layers "F.Cu" "F.Mask" "F.Paste")
			(net "GND")
			(options
				(clearance outline)
				(anchor circle)
			)
			(primitives
				(gr_poly
					(pts
						(arc
							(start -0.1778 -0.2794)
							(mid -0.249642 -0.249642)
							(end -0.2794 -0.1778)
						)
						(arc
							(start -0.2794 0.1778)
							(mid -0.249642 0.249642)
							(end -0.1778 0.2794)
						)
						(arc
							(start 0.1778 0.2794)
							(mid 0.249642 0.249642)
							(end 0.2794 0.1778)
						)
						(arc
							(start 0.2794 -0.1778)
							(mid 0.249642 -0.249642)
							(end 0.1778 -0.2794)
						)
					)
					(width 0)
					(fill yes)
				)
			)
		)
	)
	(footprint ""
		(layer "F.Cu")
		(at 45.632116 -346.071952 -90)
		(property "Reference" "R9823"
			(at 0 0 270)
			(layer "F.SilkS")
			(hide yes)
			(effects
				(font
					(size 1.27 1.27)
				)
			)
		)
		(property "Value" "0R2J-2-GP"
			(at 0.064008 -3.993896 270)
			(unlocked yes)
			(layer "F.Fab")
			(hide yes)
			(effects
				(font
					(size 1.016 1.016)
					(thickness 0.1524)
				)
			)
		)
		(property "Device Type" "R402H16"
			(at 0.064008 -5.517896 270)
			(unlocked yes)
			(layer "F.Fab")
			(hide yes)
			(effects
				(font
					(size 1.016 1.016)
					(thickness 0.1524)
				)
			)
		)
		(duplicate_pad_numbers_are_jumpers no)
		(fp_line
			(start -0.508 -0.9398)
			(end -0.508 0.9398)
			(stroke
				(width 0.1524)
				(type default)
			)
			(layer "F.SilkS")
		)
		(fp_line
			(start 0.508 -0.9398)
			(end -0.508 -0.9398)
			(stroke
				(width 0.1524)
				(type default)
			)
			(layer "F.SilkS")
		)
		(fp_rect
			(start -0.508 0.9398)
			(end 0.508 -0.9398)
			(stroke
				(width 0)
				(type default)
			)
			(fill no)
			(layer "F.CrtYd")
		)
		(fp_rect
			(start -0.508 0.9398)
			(end 0.508 -0.9398)
			(stroke
				(width 0)
				(type default)
			)
			(fill no)
			(layer "F.Fab")
		)
		(pad "1" smd custom
			(at 0 -0.4445 270)
			(size 0.1397 0.1397)
			(layers "F.Cu" "F.Mask" "F.Paste")
			(net "SSD_ACT_DR6_R")
			(options
				(clearance outline)
				(anchor circle)
			)
			(primitives
				(gr_poly
					(pts
						(arc
							(start -0.1778 -0.2794)
							(mid -0.249642 -0.249642)
							(end -0.2794 -0.1778)
						)
						(arc
							(start -0.2794 0.1778)
							(mid -0.249642 0.249642)
							(end -0.1778 0.2794)
						)
						(arc
							(start 0.1778 0.2794)
							(mid 0.249642 0.249642)
							(end 0.2794 0.1778)
						)
						(arc
							(start 0.2794 -0.1778)
							(mid 0.249642 -0.249642)
							(end 0.1778 -0.2794)
						)
					)
					(width 0)
					(fill yes)
				)
			)
		)
		(pad "2" smd custom
			(at 0 0.4445 270)
			(size 0.1397 0.1397)
			(layers "F.Cu" "F.Mask" "F.Paste")
			(net "SSD_ACT_DR6")
			(options
				(clearance outline)
				(anchor circle)
			)
			(primitives
				(gr_poly
					(pts
						(arc
							(start -0.1778 -0.2794)
							(mid -0.249642 -0.249642)
							(end -0.2794 -0.1778)
						)
						(arc
							(start -0.2794 0.1778)
							(mid -0.249642 0.249642)
							(end -0.1778 0.2794)
						)
						(arc
							(start 0.1778 0.2794)
							(mid 0.249642 0.249642)
							(end 0.2794 0.1778)
						)
						(arc
							(start 0.2794 -0.1778)
							(mid 0.249642 -0.249642)
							(end 0.1778 -0.2794)
						)
					)
					(width 0)
					(fill yes)
				)
			)
		)
	)
	(footprint ""
		(layer "F.Cu")
		(at 20.1676 -206.5528 180)
		(property "Reference" "R9252"
			(at 0 0 180)
			(layer "F.SilkS")
			(hide yes)
			(effects
				(font
					(size 1.27 1.27)
				)
			)
		)
		(property "Value" "2R2010F-GP"
			(at 0.0762 -4.5466 180)
			(unlocked yes)
			(layer "F.Fab")
			(hide yes)
			(effects
				(font
					(size 1.016 1.016)
					(thickness 0.1524)
				)
			)
		)
		(property "Device Type" "R2010H26"
			(at 0.0762 -6.1468 180)
			(unlocked yes)
			(layer "F.Fab")
			(hide yes)
			(effects
				(font
					(size 1.016 1.016)
					(thickness 0.1524)
				)
			)
		)
		(duplicate_pad_numbers_are_jumpers no)
		(fp_line
			(start 3.302 1.651)
			(end 3.302 -1.651)
			(stroke
				(width 0.1524)
				(type default)
			)
			(layer "F.SilkS")
		)
		(fp_line
			(start 3.302 -1.651)
			(end -3.302 -1.651)
			(stroke
				(width 0.1524)
				(type default)
			)
			(layer "F.SilkS")
		)
		(fp_line
			(start -3.302 1.651)
			(end 3.302 1.651)
			(stroke
				(width 0.1524)
				(type default)
			)
			(layer "F.SilkS")
		)
		(fp_line
			(start -3.302 -1.651)
			(end -3.302 1.651)
			(stroke
				(width 0.1524)
				(type default)
			)
			(layer "F.SilkS")
		)
		(fp_rect
			(start -3.3782 1.7272)
			(end 3.3782 -1.7272)
			(stroke
				(width 0)
				(type default)
			)
			(fill no)
			(layer "F.CrtYd")
		)
		(fp_poly
			(pts
				(xy 3.3782 -1.7272) (xy -3.3782 -1.7272) (xy -3.3782 1.7272) (xy 3.3782 1.7272)
			)
			(stroke
				(width 0)
				(type default)
			)
			(fill no)
			(layer "F.Fab")
		)
		(pad "1" smd rect
			(at -2.3495 0 180)
			(size 1.143 2.794)
			(layers "F.Cu" "F.Mask" "F.Paste")
			(net "P12V_SSD12")
		)
		(pad "2" smd rect
			(at 2.3495 0 180)
			(size 1.143 2.794)
			(layers "F.Cu" "F.Mask" "F.Paste")
			(net "12V_PRECH_SSD12")
		)
	)
	(footprint ""
		(layer "F.Cu")
		(at 229.67696 -447.11874)
		(property "Reference" "C9518"
			(at 0 0 0)
			(layer "F.SilkS")
			(hide yes)
			(effects
				(font
					(size 1.27 1.27)
				)
			)
		)
		(property "Value" "SCD1U16V2KX-3GP"
			(at 1.1811 -2.7051 0)
			(unlocked yes)
			(layer "F.Fab")
			(hide yes)
			(effects
				(font
					(size 1.016 1.016)
					(thickness 0.1524)
				)
			)
		)
		(property "Device Type" "C402H22"
			(at 1.1811 -4.2291 0)
			(unlocked yes)
			(layer "F.Fab")
			(hide yes)
			(effects
				(font
					(size 1.016 1.016)
					(thickness 0.1524)
				)
			)
		)
		(duplicate_pad_numbers_are_jumpers no)
		(fp_rect
			(start -0.4318 0.9525)
			(end 0.4318 -0.9525)
			(stroke
				(width 0)
				(type default)
			)
			(fill no)
			(layer "F.CrtYd")
		)
		(fp_rect
			(start -0.4318 0.9525)
			(end 0.4318 -0.9525)
			(stroke
				(width 0)
				(type default)
			)
			(fill no)
			(layer "F.Fab")
		)
		(pad "1" smd custom
			(at 0 -0.4445)
			(size 0.1524 0.1524)
			(layers "F.Cu" "F.Mask" "F.Paste")
			(net "P3V3")
			(options
				(clearance outline)
				(anchor circle)
			)
			(primitives
				(gr_poly
					(pts
						(arc
							(start 0.3048 -0.2032)
							(mid 0.275042 -0.275042)
							(end 0.2032 -0.3048)
						)
						(arc
							(start -0.2032 -0.3048)
							(mid -0.275042 -0.275042)
							(end -0.3048 -0.2032)
						)
						(arc
							(start -0.3048 0.2032)
							(mid -0.275042 0.275042)
							(end -0.2032 0.3048)
						)
						(arc
							(start 0.2032 0.3048)
							(mid 0.275042 0.275042)
							(end 0.3048 0.2032)
						)
					)
					(width 0)
					(fill yes)
				)
			)
		)
		(pad "2" smd custom
			(at 0 0.4445)
			(size 0.1524 0.1524)
			(layers "F.Cu" "F.Mask" "F.Paste")
			(net "GND")
			(options
				(clearance outline)
				(anchor circle)
			)
			(primitives
				(gr_poly
					(pts
						(arc
							(start 0.3048 -0.2032)
							(mid 0.275042 -0.275042)
							(end 0.2032 -0.3048)
						)
						(arc
							(start -0.2032 -0.3048)
							(mid -0.275042 -0.275042)
							(end -0.3048 -0.2032)
						)
						(arc
							(start -0.3048 0.2032)
							(mid -0.275042 0.275042)
							(end -0.2032 0.3048)
						)
						(arc
							(start 0.2032 0.3048)
							(mid 0.275042 0.275042)
							(end 0.3048 0.2032)
						)
					)
					(width 0)
					(fill yes)
				)
			)
		)
	)
)
